# S9S_MB_2U (Grand Teton) — schematic netlist excerpt (pin names and nets, part order shuffled) for the footprints in the layout excerpt that follows; sources: Cadence DE-HDL packaged netlist, KiCad conversion of 03242023_DA0F0TMBIJ0_F0T_Motherboard_J_brd_V01_OCP.brd

R3278  Q_RES  1K 1% CHIP  pkg 0402LF  page 166 : A = FM_P2E_EQA0 ; B = GND

U242  74LVC2G08DP  IC  pkg TSSOP8_0-65_3X3  page 165
  \1a\  = OCP_SFF_PRSNT01_R_N
  \1b\  = OCP_SFF_PRSNT23_R_N
  \2y\  = OCP_V3_2_PRSNT_ALL_R_N
  GND  = GND
  \2a\  = OCP_V3_2_PRSNT01_R_N
  \2b\  = OCP_V3_2_PRSNT23_R_N
  \1y\  = OCP_SFF_PRSNT_ALL_R_N
  VCC  = P3V3_AUX

(kicad_pcb
	(version 20260206)
	(generator "pcbnew")
	(generator_version "10.0")
	(general
		(thickness 1.6)
		(legacy_teardrops no)
	)
	(paper "A4")
	(title_block
		(title "03242023_DA0F0TMBIJ0_F0T_Motherboard_J_brd_V01_OCP.brd")
		(comment 1 "Grand Teton / footprints 2962-2963 of 6105")
	)
	(layers
		(0 "F.Cu" signal "TOP")
		(4 "In1.Cu" signal "GND")
		(6 "In2.Cu" signal "IN1")
		(8 "In3.Cu" signal "GND1")
		(10 "In4.Cu" signal "IN2")
		(12 "In5.Cu" signal "GND2")
		(14 "In6.Cu" signal "IN3")
		(16 "In7.Cu" signal "GND3")
		(18 "In8.Cu" signal "VCC")
		(20 "In9.Cu" signal "VCC1")
		(22 "In10.Cu" signal "GND4")
		(24 "In11.Cu" signal "IN4")
		(26 "In12.Cu" signal "GND5")
		(28 "In13.Cu" signal "IN5")
		(30 "In14.Cu" signal "GND6")
		(32 "In15.Cu" signal "IN6")
		(34 "In16.Cu" signal "GND7")
		(2 "B.Cu" signal "BOTTOM")
		(9 "F.Adhes" user "F.Adhesive")
		(11 "B.Adhes" user "B.Adhesive")
		(13 "F.Paste" user "Package Geometry/Pastemask Top")
		(15 "B.Paste" user "Package Geometry/Pastemask Bottom")
		(5 "F.SilkS" user "Ref Des/Silkscreen Top")
		(7 "B.SilkS" user "Ref Des/Silkscreen Bottom")
		(1 "F.Mask" user "Board Geometry/Soldermask Top")
		(3 "B.Mask" user "Board Geometry/Soldermask Bottom")
		(17 "Dwgs.User" user "User.Drawings")
		(19 "Cmts.User" user "User.Comments")
		(21 "Eco1.User" user "User.Eco1")
		(23 "Eco2.User" user "User.Eco2")
		(25 "Edge.Cuts" user "Board Geometry/Outline")
		(27 "Margin" user)
		(31 "F.CrtYd" user "Package Geometry/Place Bound Top")
		(29 "B.CrtYd" user "Package Geometry/Place Bound Bottom")
		(35 "F.Fab" user "Ref Des/Assembly Top")
		(33 "B.Fab" user "Ref Des/Assembly Bottom")
	)
	(footprint ""
		(layer "F.Cu")
		(at 21.348192 -399.532094 90)
		(property "Reference" "R3278"
			(at 0 0 90)
			(layer "F.SilkS")
			(hide yes)
			(effects
				(font
					(size 1.27 1.27)
				)
			)
		)
		(property "Value" ""
			(at 0 0 90)
			(layer "F.Fab")
			(effects
				(font
					(size 1.27 1.27)
				)
			)
		)
		(duplicate_pad_numbers_are_jumpers no)
		(fp_line
			(start 0.7874 -0.4064)
			(end 0.7874 0.4064)
			(stroke
				(width 0.1524)
				(type default)
			)
			(layer "F.SilkS")
		)
		(fp_line
			(start -0.7874 -0.4064)
			(end 0.7874 -0.4064)
			(stroke
				(width 0.1524)
				(type default)
			)
			(layer "F.SilkS")
		)
		(fp_line
			(start 0.7874 0.4064)
			(end -0.7874 0.4064)
			(stroke
				(width 0.1524)
				(type default)
			)
			(layer "F.SilkS")
		)
		(fp_line
			(start -0.7874 0.4064)
			(end -0.7874 -0.4064)
			(stroke
				(width 0.1524)
				(type default)
			)
			(layer "F.SilkS")
		)
		(fp_line
			(start -0.12065 -0.305054)
			(end -0.12065 -0.2794)
			(stroke
				(width 0.1)
				(type default)
			)
			(layer "F.Fab")
		)
		(fp_line
			(start -0.67945 -0.305054)
			(end -0.12065 -0.305054)
			(stroke
				(width 0.1)
				(type default)
			)
			(layer "F.Fab")
		)
		(fp_line
			(start 0.67945 -0.3048)
			(end 0.67945 0.3048)
			(stroke
				(width 0.1)
				(type default)
			)
			(layer "F.Fab")
		)
		(fp_line
			(start 0.12065 -0.3048)
			(end 0.67945 -0.3048)
			(stroke
				(width 0.1)
				(type default)
			)
			(layer "F.Fab")
		)
		(fp_line
			(start 0.12065 -0.2794)
			(end 0.12065 -0.3048)
			(stroke
				(width 0.1)
				(type default)
			)
			(layer "F.Fab")
		)
		(fp_line
			(start -0.12065 -0.2794)
			(end 0.12065 -0.2794)
			(stroke
				(width 0.1)
				(type default)
			)
			(layer "F.Fab")
		)
		(fp_line
			(start 0.120396 0.2794)
			(end -0.12065 0.2794)
			(stroke
				(width 0.1)
				(type default)
			)
			(layer "F.Fab")
		)
		(fp_line
			(start -0.12065 0.2794)
			(end -0.12065 0.3048)
			(stroke
				(width 0.1)
				(type default)
			)
			(layer "F.Fab")
		)
		(fp_line
			(start 0.67945 0.3048)
			(end 0.120396 0.3048)
			(stroke
				(width 0.1)
				(type default)
			)
			(layer "F.Fab")
		)
		(fp_line
			(start 0.120396 0.3048)
			(end 0.120396 0.2794)
			(stroke
				(width 0.1)
				(type default)
			)
			(layer "F.Fab")
		)
		(fp_line
			(start -0.12065 0.3048)
			(end -0.67945 0.3048)
			(stroke
				(width 0.1)
				(type default)
			)
			(layer "F.Fab")
		)
		(fp_line
			(start -0.67945 0.3048)
			(end -0.67945 -0.305054)
			(stroke
				(width 0.1)
				(type default)
			)
			(layer "F.Fab")
		)
		(pad "1" smd circle
			(at -0.40005 0 90)
			(size 0 0)
			(layers "F.Cu" "F.Mask" "F.Paste")
			(net "FM_P2E_EQA0")
		)
		(pad "2" smd circle
			(at 0.40005 0 90)
			(size 0 0)
			(layers "F.Cu" "F.Mask" "F.Paste")
			(net "GND")
		)
	)
	(footprint ""
		(layer "F.Cu")
		(at 13.12672 -74.846688)
		(property "Reference" "U242"
			(at 2.69494 1.000252 0)
			(unlocked yes)
			(layer "F.SilkS")
			(effects
				(font
					(size 0.7874 0.5842)
					(thickness 0.1524)
				)
				(justify left)
			)
		)
		(property "Value" ""
			(at 0 0 0)
			(layer "F.Fab")
			(effects
				(font
					(size 1.27 1.27)
				)
			)
		)
		(duplicate_pad_numbers_are_jumpers no)
		(fp_line
			(start -1.207008 -1.549908)
			(end -1.207008 1.549908)
			(stroke
				(width 0.1524)
				(type default)
			)
			(layer "F.SilkS")
		)
		(fp_line
			(start -1.207008 1.549908)
			(end 1.207008 1.549908)
			(stroke
				(width 0.1524)
				(type default)
			)
			(layer "F.SilkS")
		)
		(fp_line
			(start -0.762508 -1.549908)
			(end -1.207008 -1.549908)
			(stroke
				(width 0.1524)
				(type default)
			)
			(layer "F.SilkS")
		)
		(fp_line
			(start 0 -0.635)
			(end -0.762508 -1.549908)
			(stroke
				(width 0.1524)
				(type default)
			)
			(layer "F.SilkS")
		)
		(fp_line
			(start 0.762508 -1.549908)
			(end 0 -0.635)
			(stroke
				(width 0.1524)
				(type default)
			)
			(layer "F.SilkS")
		)
		(fp_line
			(start 1.207008 -1.549908)
			(end 0.762508 -1.549908)
			(stroke
				(width 0.1524)
				(type default)
			)
			(layer "F.SilkS")
		)
		(fp_line
			(start 1.207008 1.549908)
			(end 1.207008 -1.549908)
			(stroke
				(width 0.1524)
				(type default)
			)
			(layer "F.SilkS")
		)
		(fp_poly
			(pts
				(xy -1.41351 -2.42062) (xy -1.92151 -1.40462) (xy -2.42951 -2.42062)
			)
			(stroke
				(width 0)
				(type default)
			)
			(fill yes)
			(layer "F.SilkS")
		)
		(fp_line
			(start -1.549908 -1.549908)
			(end -1.549908 1.549908)
			(stroke
				(width 0.1)
				(type default)
			)
			(layer "F.Fab")
		)
		(fp_line
			(start -1.549908 1.549908)
			(end 1.549908 1.549908)
			(stroke
				(width 0.1)
				(type default)
			)
			(layer "F.Fab")
		)
		(fp_line
			(start 1.549908 -1.549908)
			(end -1.549908 -1.549908)
			(stroke
				(width 0.1)
				(type default)
			)
			(layer "F.Fab")
		)
		(fp_line
			(start 1.549908 1.549908)
			(end 1.549908 -1.549908)
			(stroke
				(width 0.1)
				(type default)
			)
			(layer "F.Fab")
		)
		(fp_poly
			(pts
				(xy -3.4036 -1.53289) (xy -3.4036 -0.51689) (xy -2.3876 -1.02489)
			)
			(stroke
				(width 0)
				(type default)
			)
			(fill yes)
			(layer "F.Fab")
		)
		(pad "1" smd rect
			(at -1.774952 -1.02489 270)
			(size 0.508 0.8636)
			(layers "F.Cu" "F.Mask" "F.Paste")
			(net "OCP_SFF_PRSNT01_R_N")
		)
		(pad "2" smd rect
			(at -1.774952 -0.32512 270)
			(size 0.4064 0.8636)
			(layers "F.Cu" "F.Mask" "F.Paste")
			(net "OCP_SFF_PRSNT23_R_N")
		)
		(pad "3" smd rect
			(at -1.774952 0.32512 270)
			(size 0.4064 0.8636)
			(layers "F.Cu" "F.Mask" "F.Paste")
			(net "OCP_V3_2_PRSNT_ALL_R_N")
		)
		(pad "4" smd rect
			(at -1.774952 1.02489 270)
			(size 0.508 0.8636)
			(layers "F.Cu" "F.Mask" "F.Paste")
			(net "GND")
		)
		(pad "5" smd rect
			(at 1.774952 1.02489 270)
			(size 0.508 0.8636)
			(layers "F.Cu" "F.Mask" "F.Paste")
			(net "OCP_V3_2_PRSNT01_R_N")
		)
		(pad "6" smd rect
			(at 1.774952 0.32512 270)
			(size 0.4064 0.8636)
			(layers "F.Cu" "F.Mask" "F.Paste")
			(net "OCP_V3_2_PRSNT23_R_N")
		)
		(pad "7" smd rect
			(at 1.774952 -0.32512 270)
			(size 0.4064 0.8636)
			(layers "F.Cu" "F.Mask" "F.Paste")
			(net "OCP_SFF_PRSNT_ALL_R_N")
		)
		(pad "8" smd rect
			(at 1.774952 -1.02489 270)
			(size 0.508 0.8636)
			(layers "F.Cu" "F.Mask" "F.Paste")
			(net "P3V3_AUX")
		)
	)
)
